# BASEBOARD_FAB2 (Tioga Pass) — schematic netlist excerpt (pin names and nets, part order shuffled) for the footprints in the layout excerpt that follows; sources: Cadence DE-HDL packaged netlist, KiCad conversion of Wiwynn_Tioga_Pass_MB.brd

C6F1  CAP_A  0.1UF 16V 10% X7R  pkg 0402V  page 104 : A = P3V3 ; B = GND
C8F2  CAP  1000PF 50V 10% X7R  pkg 0402LF  page 240 : A = PWRGD_P3V3_STBY_R ; B = GND
R7D32  RES  100.0 1% CHIP  pkg 0402  page 92 : A = P0V7_GTL2104_VREF_0 ; B = GND

(kicad_pcb
	(version 20260206)
	(generator "pcbnew")
	(generator_version "10.0")
	(general
		(thickness 1.6)
		(legacy_teardrops no)
	)
	(paper "A4")
	(title_block
		(title "Wiwynn_Tioga_Pass_MB.brd")
		(comment 1 "Tioga Pass / footprints 550-552 of 4770")
	)
	(layers
		(0 "F.Cu" signal "TOP")
		(4 "In1.Cu" signal "L2GND")
		(6 "In2.Cu" signal "L3")
		(8 "In3.Cu" signal "L4GND")
		(10 "In4.Cu" signal "L5")
		(12 "In5.Cu" signal "L6GND")
		(14 "In6.Cu" signal "L7VCC")
		(16 "In7.Cu" signal "L8VCC")
		(18 "In8.Cu" signal "L9GND")
		(20 "In9.Cu" signal "L10")
		(22 "In10.Cu" signal "L11GND")
		(24 "In11.Cu" signal "L12")
		(26 "In12.Cu" signal "L13GND")
		(2 "B.Cu" signal "BOTTOM")
		(9 "F.Adhes" user "F.Adhesive")
		(11 "B.Adhes" user "B.Adhesive")
		(13 "F.Paste" user "Package Geometry/Pastemask Top")
		(15 "B.Paste" user "Package Geometry/Pastemask Bottom")
		(5 "F.SilkS" user "Ref Des/Silkscreen Top")
		(7 "B.SilkS" user "Ref Des/Silkscreen Bottom")
		(1 "F.Mask" user "Board Geometry/Soldermask Top")
		(3 "B.Mask" user "Board Geometry/Soldermask Bottom")
		(17 "Dwgs.User" user "User.Drawings")
		(19 "Cmts.User" user "User.Comments")
		(21 "Eco1.User" user "User.Eco1")
		(23 "Eco2.User" user "User.Eco2")
		(25 "Edge.Cuts" user "Board Geometry/Outline")
		(27 "Margin" user)
		(31 "F.CrtYd" user "Package Geometry/Place Bound Top")
		(29 "B.CrtYd" user "Package Geometry/Place Bound Bottom")
		(35 "F.Fab" user "Ref Des/Assembly Top")
		(33 "B.Fab" user "Ref Des/Assembly Bottom")
	)
	(footprint ""
		(layer "F.Cu")
		(at 465.582 -22.225 -90)
		(property "Reference" "C8F2"
			(at 0 0 270)
			(layer "F.SilkS")
			(hide yes)
			(effects
				(font
					(size 1.27 1.27)
				)
			)
		)
		(property "Value" ""
			(at 0 0 270)
			(layer "F.Fab")
			(effects
				(font
					(size 1.27 1.27)
				)
			)
		)
		(duplicate_pad_numbers_are_jumpers no)
		(fp_rect
			(start 0.3048 0.9906)
			(end -0.3048 -0.1016)
			(stroke
				(width 0)
				(type default)
			)
			(fill no)
			(layer "F.CrtYd")
		)
		(fp_line
			(start -0.3048 0.9906)
			(end 0.3048 0.9906)
			(stroke
				(width 0.1)
				(type default)
			)
			(layer "F.Fab")
		)
		(fp_line
			(start 0.3048 0.9906)
			(end 0.3048 -0.1016)
			(stroke
				(width 0.1)
				(type default)
			)
			(layer "F.Fab")
		)
		(fp_line
			(start -0.3048 -0.1016)
			(end -0.3048 0.9906)
			(stroke
				(width 0.1)
				(type default)
			)
			(layer "F.Fab")
		)
		(fp_line
			(start 0.3048 -0.1016)
			(end -0.3048 -0.1016)
			(stroke
				(width 0.1)
				(type default)
			)
			(layer "F.Fab")
		)
		(pad "1" smd rect
			(at 0 0 270)
			(size 0.508 0.508)
			(layers "F.Cu" "F.Mask" "F.Paste")
			(net "PWRGD_P3V3_STBY_R")
		)
		(pad "2" smd rect
			(at 0 0.889 270)
			(size 0.508 0.508)
			(layers "F.Cu" "F.Mask" "F.Paste")
			(net "GND")
		)
		(zone
			(layer "F.Cu")
			(hatch none 0.5)
			(connect_pads
				(clearance 0)
			)
			(min_thickness 0.25)
			(keepout
				(tracks allowed)
				(vias not_allowed)
				(pads allowed)
				(copperpour not_allowed)
				(footprints allowed)
			)
			(placement
				(enabled no)
				(sheetname "")
			)
			(fill
				(thermal_gap 0.5)
				(thermal_bridge_width 0.5)
				(island_removal_mode 0)
			)
			(polygon
				(pts
					(xy 464.947 -21.971) (xy 465.328 -21.971) (xy 465.328 -22.479) (xy 464.947 -22.479)
				)
			)
		)
		(zone
			(layer "F.Cu")
			(hatch none 0.5)
			(connect_pads
				(clearance 0)
			)
			(min_thickness 0.25)
			(keepout
				(tracks not_allowed)
				(vias allowed)
				(pads allowed)
				(copperpour not_allowed)
				(footprints allowed)
			)
			(placement
				(enabled no)
				(sheetname "")
			)
			(fill
				(thermal_gap 0.5)
				(thermal_bridge_width 0.5)
				(island_removal_mode 0)
			)
			(polygon
				(pts
					(xy 464.947 -21.971) (xy 465.328 -21.971) (xy 465.328 -22.479) (xy 464.947 -22.479)
				)
			)
		)
	)
	(footprint ""
		(layer "F.Cu")
		(at 317.7286 -31.8516 90)
		(property "Reference" "C6F1"
			(at 0 0 90)
			(layer "F.SilkS")
			(hide yes)
			(effects
				(font
					(size 1.27 1.27)
				)
			)
		)
		(property "Value" ""
			(at 0 0 90)
			(layer "F.Fab")
			(effects
				(font
					(size 1.27 1.27)
				)
			)
		)
		(duplicate_pad_numbers_are_jumpers no)
		(fp_poly
			(pts
				(xy 0.3048 -0.1016) (xy 0.3048 0.9906) (xy -0.3048 0.9906) (xy -0.3048 -0.1016)
			)
			(stroke
				(width 0)
				(type default)
			)
			(fill no)
			(layer "F.CrtYd")
		)
		(fp_line
			(start 0.3048 -0.1016)
			(end -0.3048 -0.1016)
			(stroke
				(width 0.1)
				(type default)
			)
			(layer "F.Fab")
		)
		(fp_line
			(start -0.3048 -0.1016)
			(end -0.3048 0.9906)
			(stroke
				(width 0.1)
				(type default)
			)
			(layer "F.Fab")
		)
		(fp_line
			(start 0.3048 0.9906)
			(end 0.3048 -0.1016)
			(stroke
				(width 0.1)
				(type default)
			)
			(layer "F.Fab")
		)
		(fp_line
			(start -0.3048 0.9906)
			(end 0.3048 0.9906)
			(stroke
				(width 0.1)
				(type default)
			)
			(layer "F.Fab")
		)
		(pad "1" smd rect
			(at 0 0 90)
			(size 0.508 0.508)
			(layers "F.Cu" "F.Mask" "F.Paste")
			(net "P3V3")
		)
		(pad "2" smd rect
			(at 0 0.889 90)
			(size 0.508 0.508)
			(layers "F.Cu" "F.Mask" "F.Paste")
			(net "GND")
		)
		(zone
			(layer "F.Cu")
			(hatch none 0.5)
			(connect_pads
				(clearance 0)
			)
			(min_thickness 0.25)
			(keepout
				(tracks allowed)
				(vias not_allowed)
				(pads allowed)
				(copperpour not_allowed)
				(footprints allowed)
			)
			(placement
				(enabled no)
				(sheetname "")
			)
			(fill
				(thermal_gap 0.5)
				(thermal_bridge_width 0.5)
				(island_removal_mode 0)
			)
			(polygon
				(pts
					(xy 317.9826 -31.5976) (xy 317.9826 -32.1056) (xy 318.3636 -32.1056) (xy 318.3636 -31.5976)
				)
			)
		)
		(zone
			(layer "F.Cu")
			(hatch none 0.5)
			(connect_pads
				(clearance 0)
			)
			(min_thickness 0.25)
			(keepout
				(tracks not_allowed)
				(vias allowed)
				(pads allowed)
				(copperpour not_allowed)
				(footprints allowed)
			)
			(placement
				(enabled no)
				(sheetname "")
			)
			(fill
				(thermal_gap 0.5)
				(thermal_bridge_width 0.5)
				(island_removal_mode 0)
			)
			(polygon
				(pts
					(xy 318.3636 -31.5976) (xy 318.3636 -32.1056) (xy 317.9826 -32.1056) (xy 317.9826 -31.5976)
				)
			)
		)
	)
	(footprint ""
		(layer "F.Cu")
		(at 389.0645 -79.8322 -90)
		(property "Reference" "R7D32"
			(at 0 0 270)
			(layer "F.SilkS")
			(hide yes)
			(effects
				(font
					(size 1.27 1.27)
				)
			)
		)
		(property "Value" ""
			(at 0 0 270)
			(layer "F.Fab")
			(effects
				(font
					(size 1.27 1.27)
				)
			)
		)
		(duplicate_pad_numbers_are_jumpers no)
		(fp_poly
			(pts
				(xy -0.2794 -0.1016) (xy 0.2794 -0.1016) (xy 0.2794 0.9906) (xy -0.2794 0.9906)
			)
			(stroke
				(width 0)
				(type default)
			)
			(fill no)
			(layer "F.CrtYd")
		)
		(fp_line
			(start -0.2794 0.9906)
			(end 0.2794 0.9906)
			(stroke
				(width 0.1)
				(type default)
			)
			(layer "F.Fab")
		)
		(fp_line
			(start 0.2794 0.9906)
			(end 0.2794 -0.1016)
			(stroke
				(width 0.1)
				(type default)
			)
			(layer "F.Fab")
		)
		(fp_line
			(start -0.2794 -0.1016)
			(end -0.2794 0.9906)
			(stroke
				(width 0.1)
				(type default)
			)
			(layer "F.Fab")
		)
		(fp_line
			(start 0.2794 -0.1016)
			(end -0.2794 -0.1016)
			(stroke
				(width 0.1)
				(type default)
			)
			(layer "F.Fab")
		)
		(pad "1" smd rect
			(at 0 0 270)
			(size 0.508 0.508)
			(layers "F.Cu" "F.Mask" "F.Paste")
			(net "P0V7_GTL2104_VREF_0")
		)
		(pad "2" smd rect
			(at 0 0.889 270)
			(size 0.508 0.508)
			(layers "F.Cu" "F.Mask" "F.Paste")
			(net "GND")
		)
		(zone
			(layer "F.Cu")
			(hatch none 0.5)
			(connect_pads
				(clearance 0)
			)
			(min_thickness 0.25)
			(keepout
				(tracks not_allowed)
				(vias allowed)
				(pads allowed)
				(copperpour not_allowed)
				(footprints allowed)
			)
			(placement
				(enabled no)
				(sheetname "")
			)
			(fill
				(thermal_gap 0.5)
				(thermal_bridge_width 0.5)
				(island_removal_mode 0)
			)
			(polygon
				(pts
					(xy 388.4295 -80.0862) (xy 388.4295 -79.5782) (xy 388.8105 -79.5782) (xy 388.8105 -80.0862)
				)
			)
		)
		(zone
			(layer "F.Cu")
			(hatch none 0.5)
			(connect_pads
				(clearance 0)
			)
			(min_thickness 0.25)
			(keepout
				(tracks allowed)
				(vias not_allowed)
				(pads allowed)
				(copperpour not_allowed)
				(footprints allowed)
			)
			(placement
				(enabled no)
				(sheetname "")
			)
			(fill
				(thermal_gap 0.5)
				(thermal_bridge_width 0.5)
				(island_removal_mode 0)
			)
			(polygon
				(pts
					(xy 388.8105 -80.0862) (xy 388.8105 -79.5782) (xy 388.4295 -79.5782) (xy 388.4295 -80.0862)
				)
			)
		)
	)
)
